(kicad_pcb
	(version 20260206)
	(generator "pcbnew")
	(generator_version "10.0")
	(general
		(thickness 1.6)
		(legacy_teardrops no)
	)
	(paper "A4")
	(title_block
		(title "03242023_DA0F0TMBIJ0_F0T_Motherboard_J_brd_V01_OCP.brd")
		(comment 1 "Grand Teton / footprints 5181-5186 of 6105")
	)
	(layers
		(0 "F.Cu" signal "TOP")
		(4 "In1.Cu" signal "GND")
		(6 "In2.Cu" signal "IN1")
		(8 "In3.Cu" signal "GND1")
		(10 "In4.Cu" signal "IN2")
		(12 "In5.Cu" signal "GND2")
		(14 "In6.Cu" signal "IN3")
		(16 "In7.Cu" signal "GND3")
		(18 "In8.Cu" signal "VCC")
		(20 "In9.Cu" signal "VCC1")
		(22 "In10.Cu" signal "GND4")
		(24 "In11.Cu" signal "IN4")
		(26 "In12.Cu" signal "GND5")
		(28 "In13.Cu" signal "IN5")
		(30 "In14.Cu" signal "GND6")
		(32 "In15.Cu" signal "IN6")
		(34 "In16.Cu" signal "GND7")
		(2 "B.Cu" signal "BOTTOM")
		(9 "F.Adhes" user "F.Adhesive")
		(11 "B.Adhes" user "B.Adhesive")
		(13 "F.Paste" user "Package Geometry/Pastemask Top")
		(15 "B.Paste" user "Package Geometry/Pastemask Bottom")
		(5 "F.SilkS" user "Ref Des/Silkscreen Top")
		(7 "B.SilkS" user "Ref Des/Silkscreen Bottom")
		(1 "F.Mask" user "Board Geometry/Soldermask Top")
		(3 "B.Mask" user "Board Geometry/Soldermask Bottom")
		(17 "Dwgs.User" user "User.Drawings")
		(19 "Cmts.User" user "User.Comments")
		(21 "Eco1.User" user "User.Eco1")
		(23 "Eco2.User" user "User.Eco2")
		(25 "Edge.Cuts" user "Board Geometry/Outline")
		(27 "Margin" user)
		(31 "F.CrtYd" user "Package Geometry/Place Bound Top")
		(29 "B.CrtYd" user "Package Geometry/Place Bound Bottom")
		(35 "F.Fab" user "Ref Des/Assembly Top")
		(33 "B.Fab" user "Ref Des/Assembly Bottom")
	)
	(footprint ""
		(layer "B.Cu")
		(at 119.07266 -334.693514 -90)
		(property "Reference" "PR299"
			(at 0 0 90)
			(layer "B.SilkS")
			(hide yes)
			(effects
				(font
					(size 1.27 1.27)
				)
				(justify mirror)
			)
		)
		(property "Value" ""
			(at 0 0 90)
			(layer "B.Fab")
			(effects
				(font
					(size 1.27 1.27)
				)
				(justify mirror)
			)
		)
		(duplicate_pad_numbers_are_jumpers no)
		(fp_line
			(start -0.7874 0.4064)
			(end 0.7874 0.4064)
			(stroke
				(width 0.1524)
				(type default)
			)
			(layer "B.SilkS")
		)
		(fp_line
			(start 0.7874 0.4064)
			(end 0.7874 -0.4064)
			(stroke
				(width 0.1524)
				(type default)
			)
			(layer "B.SilkS")
		)
		(fp_line
			(start -0.7874 -0.4064)
			(end -0.7874 0.4064)
			(stroke
				(width 0.1524)
				(type default)
			)
			(layer "B.SilkS")
		)
		(fp_line
			(start 0.7874 -0.4064)
			(end -0.7874 -0.4064)
			(stroke
				(width 0.1524)
				(type default)
			)
			(layer "B.SilkS")
		)
		(fp_line
			(start -0.67945 0.3048)
			(end -0.120396 0.3048)
			(stroke
				(width 0.1)
				(type default)
			)
			(layer "B.Fab")
		)
		(fp_line
			(start -0.120396 0.3048)
			(end -0.120396 0.2794)
			(stroke
				(width 0.1)
				(type default)
			)
			(layer "B.Fab")
		)
		(fp_line
			(start 0.12065 0.3048)
			(end 0.67945 0.3048)
			(stroke
				(width 0.1)
				(type default)
			)
			(layer "B.Fab")
		)
		(fp_line
			(start 0.67945 0.3048)
			(end 0.67945 -0.305054)
			(stroke
				(width 0.1)
				(type default)
			)
			(layer "B.Fab")
		)
		(fp_line
			(start -0.120396 0.2794)
			(end 0.12065 0.2794)
			(stroke
				(width 0.1)
				(type default)
			)
			(layer "B.Fab")
		)
		(fp_line
			(start 0.12065 0.2794)
			(end 0.12065 0.3048)
			(stroke
				(width 0.1)
				(type default)
			)
			(layer "B.Fab")
		)
		(fp_line
			(start -0.12065 -0.2794)
			(end -0.12065 -0.3048)
			(stroke
				(width 0.1)
				(type default)
			)
			(layer "B.Fab")
		)
		(fp_line
			(start 0.12065 -0.2794)
			(end -0.12065 -0.2794)
			(stroke
				(width 0.1)
				(type default)
			)
			(layer "B.Fab")
		)
		(fp_line
			(start -0.67945 -0.3048)
			(end -0.67945 0.3048)
			(stroke
				(width 0.1)
				(type default)
			)
			(layer "B.Fab")
		)
		(fp_line
			(start -0.12065 -0.3048)
			(end -0.67945 -0.3048)
			(stroke
				(width 0.1)
				(type default)
			)
			(layer "B.Fab")
		)
		(fp_line
			(start 0.12065 -0.305054)
			(end 0.12065 -0.2794)
			(stroke
				(width 0.1)
				(type default)
			)
			(layer "B.Fab")
		)
		(fp_line
			(start 0.67945 -0.305054)
			(end 0.12065 -0.305054)
			(stroke
				(width 0.1)
				(type default)
			)
			(layer "B.Fab")
		)
		(pad "1" smd circle
			(at 0.40005 0 90)
			(size 0 0)
			(layers "B.Cu" "B.Mask" "B.Paste")
			(net "PVCCIN_CPU1_PVCC")
		)
		(pad "2" smd circle
			(at -0.40005 0 90)
			(size 0 0)
			(layers "B.Cu" "B.Mask" "B.Paste")
			(net "PVCCIN_CPU1_VDD4")
		)
	)
	(footprint ""
		(layer "B.Cu")
		(at 422.50487 -353.25939 -90)
		(property "Reference" "PC1187_P0_3"
			(at 0 0 90)
			(layer "B.SilkS")
			(hide yes)
			(effects
				(font
					(size 1.27 1.27)
				)
				(justify mirror)
			)
		)
		(property "Value" ""
			(at 0 0 90)
			(layer "B.Fab")
			(effects
				(font
					(size 1.27 1.27)
				)
				(justify mirror)
			)
		)
		(duplicate_pad_numbers_are_jumpers no)
		(fp_line
			(start -1.524 0.762)
			(end 1.524 0.762)
			(stroke
				(width 0.1524)
				(type default)
			)
			(layer "B.SilkS")
		)
		(fp_line
			(start 1.524 0.762)
			(end 1.524 -0.762)
			(stroke
				(width 0.1524)
				(type default)
			)
			(layer "B.SilkS")
		)
		(fp_line
			(start -1.524 -0.762)
			(end -1.524 0.762)
			(stroke
				(width 0.1524)
				(type default)
			)
			(layer "B.SilkS")
		)
		(fp_line
			(start 1.524 -0.762)
			(end -1.524 -0.762)
			(stroke
				(width 0.1524)
				(type default)
			)
			(layer "B.SilkS")
		)
		(fp_line
			(start -1.1049 0.724916)
			(end -1.1049 -0.724916)
			(stroke
				(width 0.1)
				(type default)
			)
			(layer "B.Fab")
		)
		(fp_line
			(start 1.1049 0.724916)
			(end -1.1049 0.724916)
			(stroke
				(width 0.1)
				(type default)
			)
			(layer "B.Fab")
		)
		(fp_line
			(start -1.1049 -0.724916)
			(end 1.1049 -0.724916)
			(stroke
				(width 0.1)
				(type default)
			)
			(layer "B.Fab")
		)
		(fp_line
			(start 1.1049 -0.724916)
			(end 1.1049 0.724916)
			(stroke
				(width 0.1)
				(type default)
			)
			(layer "B.Fab")
		)
		(pad "1" smd rect
			(at 0.889 0 270)
			(size 1.016 1.27)
			(layers "B.Cu" "B.Mask" "B.Paste")
			(net "PVCCFA_EHV_FIVRA_CPU0")
		)
		(pad "2" smd rect
			(at -0.889 0 270)
			(size 1.016 1.27)
			(layers "B.Cu" "B.Mask" "B.Paste")
			(net "GND")
		)
	)
	(footprint ""
		(layer "B.Cu")
		(at 328.142092 -66.244724 45)
		(property "Reference" "C1260"
			(at 0 0 45)
			(layer "B.SilkS")
			(hide yes)
			(effects
				(font
					(size 1.27 1.27)
				)
				(justify mirror)
			)
		)
		(property "Value" ""
			(at 0 0 45)
			(layer "B.Fab")
			(effects
				(font
					(size 1.27 1.27)
				)
				(justify mirror)
			)
		)
		(duplicate_pad_numbers_are_jumpers no)
		(fp_line
			(start -1.295492 -0.584255)
			(end -1.295492 0.584255)
			(stroke
				(width 0.1524)
				(type default)
			)
			(layer "B.SilkS")
		)
		(fp_line
			(start -1.295492 0.584255)
			(end 1.295492 0.584255)
			(stroke
				(width 0.1524)
				(type default)
			)
			(layer "B.SilkS")
		)
		(fp_line
			(start 0 -0.584076)
			(end 0 0.584076)
			(stroke
				(width 0.1524)
				(type default)
			)
			(layer "B.SilkS")
		)
		(fp_line
			(start 1.295492 -0.584255)
			(end -1.295492 -0.584255)
			(stroke
				(width 0.1524)
				(type default)
			)
			(layer "B.SilkS")
		)
		(fp_line
			(start 1.295492 0.584255)
			(end 1.295492 -0.584255)
			(stroke
				(width 0.1524)
				(type default)
			)
			(layer "B.SilkS")
		)
		(fp_line
			(start -1.193835 -0.406446)
			(end -1.193835 0.406446)
			(stroke
				(width 0.1)
				(type default)
			)
			(layer "B.Fab")
		)
		(fp_line
			(start -0.863541 -0.457275)
			(end -0.863721 -0.406446)
			(stroke
				(width 0.1)
				(type default)
			)
			(layer "B.Fab")
		)
		(fp_line
			(start -0.863721 -0.406446)
			(end -1.193835 -0.406446)
			(stroke
				(width 0.1)
				(type default)
			)
			(layer "B.Fab")
		)
		(fp_line
			(start -1.193835 0.406446)
			(end -0.863721 0.406446)
			(stroke
				(width 0.1)
				(type default)
			)
			(layer "B.Fab")
		)
		(fp_line
			(start -0.863721 0.406446)
			(end -0.863541 0.457275)
			(stroke
				(width 0.1)
				(type default)
			)
			(layer "B.Fab")
		)
		(fp_line
			(start -0.863541 0.457275)
			(end 0.863541 0.457275)
			(stroke
				(width 0.1)
				(type default)
			)
			(layer "B.Fab")
		)
		(fp_line
			(start 0.863541 -0.457275)
			(end -0.863541 -0.457275)
			(stroke
				(width 0.1)
				(type default)
			)
			(layer "B.Fab")
		)
		(fp_line
			(start 0.863721 -0.406446)
			(end 0.863541 -0.457275)
			(stroke
				(width 0.1)
				(type default)
			)
			(layer "B.Fab")
		)
		(fp_line
			(start 1.193835 -0.406446)
			(end 0.863721 -0.406446)
			(stroke
				(width 0.1)
				(type default)
			)
			(layer "B.Fab")
		)
		(fp_line
			(start 0.863721 0.406446)
			(end 1.193835 0.406446)
			(stroke
				(width 0.1)
				(type default)
			)
			(layer "B.Fab")
		)
		(fp_line
			(start 0.863541 0.457275)
			(end 0.863721 0.406446)
			(stroke
				(width 0.1)
				(type default)
			)
			(layer "B.Fab")
		)
		(fp_line
			(start 1.193835 0.406446)
			(end 1.193835 -0.406446)
			(stroke
				(width 0.1)
				(type default)
			)
			(layer "B.Fab")
		)
		(pad "1" smd rect
			(at 0.7366 0 315)
			(size 0.7112 0.8128)
			(layers "B.Cu" "B.Mask" "B.Paste")
			(net "P1V05_PCH_PLL_AUX")
		)
		(pad "2" smd rect
			(at -0.7366 0 315)
			(size 0.7112 0.8128)
			(layers "B.Cu" "B.Mask" "B.Paste")
			(net "GND")
		)
	)
	(footprint ""
		(layer "B.Cu")
		(at 448.186556 -318.908176 90)
		(property "Reference" "R889"
			(at 0 0 90)
			(layer "B.SilkS")
			(hide yes)
			(effects
				(font
					(size 1.27 1.27)
				)
				(justify mirror)
			)
		)
		(property "Value" ""
			(at 0 0 90)
			(layer "B.Fab")
			(effects
				(font
					(size 1.27 1.27)
				)
				(justify mirror)
			)
		)
		(duplicate_pad_numbers_are_jumpers no)
		(fp_line
			(start 0.7874 -0.4064)
			(end -0.7874 -0.4064)
			(stroke
				(width 0.1524)
				(type default)
			)
			(layer "B.SilkS")
		)
		(fp_line
			(start -0.7874 -0.4064)
			(end -0.7874 0.4064)
			(stroke
				(width 0.1524)
				(type default)
			)
			(layer "B.SilkS")
		)
		(fp_line
			(start 0.7874 0.4064)
			(end 0.7874 -0.4064)
			(stroke
				(width 0.1524)
				(type default)
			)
			(layer "B.SilkS")
		)
		(fp_line
			(start -0.7874 0.4064)
			(end 0.7874 0.4064)
			(stroke
				(width 0.1524)
				(type default)
			)
			(layer "B.SilkS")
		)
		(fp_line
			(start 0.67945 -0.305054)
			(end 0.12065 -0.305054)
			(stroke
				(width 0.1)
				(type default)
			)
			(layer "B.Fab")
		)
		(fp_line
			(start 0.12065 -0.305054)
			(end 0.12065 -0.2794)
			(stroke
				(width 0.1)
				(type default)
			)
			(layer "B.Fab")
		)
		(fp_line
			(start -0.12065 -0.3048)
			(end -0.67945 -0.3048)
			(stroke
				(width 0.1)
				(type default)
			)
			(layer "B.Fab")
		)
		(fp_line
			(start -0.67945 -0.3048)
			(end -0.67945 0.3048)
			(stroke
				(width 0.1)
				(type default)
			)
			(layer "B.Fab")
		)
		(fp_line
			(start 0.12065 -0.2794)
			(end -0.12065 -0.2794)
			(stroke
				(width 0.1)
				(type default)
			)
			(layer "B.Fab")
		)
		(fp_line
			(start -0.12065 -0.2794)
			(end -0.12065 -0.3048)
			(stroke
				(width 0.1)
				(type default)
			)
			(layer "B.Fab")
		)
		(fp_line
			(start 0.12065 0.2794)
			(end 0.12065 0.3048)
			(stroke
				(width 0.1)
				(type default)
			)
			(layer "B.Fab")
		)
		(fp_line
			(start -0.120396 0.2794)
			(end 0.12065 0.2794)
			(stroke
				(width 0.1)
				(type default)
			)
			(layer "B.Fab")
		)
		(fp_line
			(start 0.67945 0.3048)
			(end 0.67945 -0.305054)
			(stroke
				(width 0.1)
				(type default)
			)
			(layer "B.Fab")
		)
		(fp_line
			(start 0.12065 0.3048)
			(end 0.67945 0.3048)
			(stroke
				(width 0.1)
				(type default)
			)
			(layer "B.Fab")
		)
		(fp_line
			(start -0.120396 0.3048)
			(end -0.120396 0.2794)
			(stroke
				(width 0.1)
				(type default)
			)
			(layer "B.Fab")
		)
		(fp_line
			(start -0.67945 0.3048)
			(end -0.120396 0.3048)
			(stroke
				(width 0.1)
				(type default)
			)
			(layer "B.Fab")
		)
		(pad "1" smd circle
			(at 0.40005 0 270)
			(size 0 0)
			(layers "B.Cu" "B.Mask" "B.Paste")
			(net "PWRGD_CHG_CPU0_DIMM1")
		)
		(pad "2" smd circle
			(at -0.40005 0 270)
			(size 0 0)
			(layers "B.Cu" "B.Mask" "B.Paste")
			(net "PWRGD_FAIL_CPU0_GH")
		)
	)
	(footprint ""
		(layer "B.Cu")
		(at 337.31708 -45.141134 -90)
		(property "Reference" "C1242"
			(at 0 0 90)
			(layer "B.SilkS")
			(hide yes)
			(effects
				(font
					(size 1.27 1.27)
				)
				(justify mirror)
			)
		)
		(property "Value" ""
			(at 0 0 90)
			(layer "B.Fab")
			(effects
				(font
					(size 1.27 1.27)
				)
				(justify mirror)
			)
		)
		(duplicate_pad_numbers_are_jumpers no)
		(fp_line
			(start -0.7874 0.4064)
			(end 0.7874 0.4064)
			(stroke
				(width 0.1524)
				(type default)
			)
			(layer "B.SilkS")
		)
		(fp_line
			(start 0.7874 0.4064)
			(end 0.7874 -0.4064)
			(stroke
				(width 0.1524)
				(type default)
			)
			(layer "B.SilkS")
		)
		(fp_line
			(start -0.7874 -0.4064)
			(end -0.7874 0.4064)
			(stroke
				(width 0.1524)
				(type default)
			)
			(layer "B.SilkS")
		)
		(fp_line
			(start 0.7874 -0.4064)
			(end -0.7874 -0.4064)
			(stroke
				(width 0.1524)
				(type default)
			)
			(layer "B.SilkS")
		)
		(fp_line
			(start -0.67945 0.3048)
			(end -0.120396 0.3048)
			(stroke
				(width 0.1)
				(type default)
			)
			(layer "B.Fab")
		)
		(fp_line
			(start -0.120396 0.3048)
			(end -0.120396 0.2794)
			(stroke
				(width 0.1)
				(type default)
			)
			(layer "B.Fab")
		)
		(fp_line
			(start 0.12065 0.3048)
			(end 0.67945 0.3048)
			(stroke
				(width 0.1)
				(type default)
			)
			(layer "B.Fab")
		)
		(fp_line
			(start 0.67945 0.3048)
			(end 0.67945 -0.305054)
			(stroke
				(width 0.1)
				(type default)
			)
			(layer "B.Fab")
		)
		(fp_line
			(start -0.120396 0.2794)
			(end 0.12065 0.2794)
			(stroke
				(width 0.1)
				(type default)
			)
			(layer "B.Fab")
		)
		(fp_line
			(start 0.12065 0.2794)
			(end 0.12065 0.3048)
			(stroke
				(width 0.1)
				(type default)
			)
			(layer "B.Fab")
		)
		(fp_line
			(start -0.12065 -0.2794)
			(end -0.12065 -0.3048)
			(stroke
				(width 0.1)
				(type default)
			)
			(layer "B.Fab")
		)
		(fp_line
			(start 0.12065 -0.2794)
			(end -0.12065 -0.2794)
			(stroke
				(width 0.1)
				(type default)
			)
			(layer "B.Fab")
		)
		(fp_line
			(start -0.67945 -0.3048)
			(end -0.67945 0.3048)
			(stroke
				(width 0.1)
				(type default)
			)
			(layer "B.Fab")
		)
		(fp_line
			(start -0.12065 -0.3048)
			(end -0.67945 -0.3048)
			(stroke
				(width 0.1)
				(type default)
			)
			(layer "B.Fab")
		)
		(fp_line
			(start 0.12065 -0.305054)
			(end 0.12065 -0.2794)
			(stroke
				(width 0.1)
				(type default)
			)
			(layer "B.Fab")
		)
		(fp_line
			(start 0.67945 -0.305054)
			(end 0.12065 -0.305054)
			(stroke
				(width 0.1)
				(type default)
			)
			(layer "B.Fab")
		)
		(pad "1" smd circle
			(at 0.40005 0 90)
			(size 0 0)
			(layers "B.Cu" "B.Mask" "B.Paste")
			(net "P1V05_PCH_AUX")
		)
		(pad "2" smd circle
			(at -0.40005 0 90)
			(size 0 0)
			(layers "B.Cu" "B.Mask" "B.Paste")
			(net "GND")
		)
	)
	(footprint ""
		(layer "B.Cu")
		(at 281.100784 -193.669666 -90)
		(property "Reference" "R254"
			(at 0 0 90)
			(layer "B.SilkS")
			(hide yes)
			(effects
				(font
					(size 1.27 1.27)
				)
				(justify mirror)
			)
		)
		(property "Value" ""
			(at 0 0 90)
			(layer "B.Fab")
			(effects
				(font
					(size 1.27 1.27)
				)
				(justify mirror)
			)
		)
		(duplicate_pad_numbers_are_jumpers no)
		(fp_line
			(start -0.7874 0.4064)
			(end 0.7874 0.4064)
			(stroke
				(width 0.1524)
				(type default)
			)
			(layer "B.SilkS")
		)
		(fp_line
			(start 0.7874 0.4064)
			(end 0.7874 -0.4064)
			(stroke
				(width 0.1524)
				(type default)
			)
			(layer "B.SilkS")
		)
		(fp_line
			(start -0.7874 -0.4064)
			(end -0.7874 0.4064)
			(stroke
				(width 0.1524)
				(type default)
			)
			(layer "B.SilkS")
		)
		(fp_line
			(start 0.7874 -0.4064)
			(end -0.7874 -0.4064)
			(stroke
				(width 0.1524)
				(type default)
			)
			(layer "B.SilkS")
		)
		(fp_line
			(start -0.67945 0.3048)
			(end -0.120396 0.3048)
			(stroke
				(width 0.1)
				(type default)
			)
			(layer "B.Fab")
		)
		(fp_line
			(start -0.120396 0.3048)
			(end -0.120396 0.2794)
			(stroke
				(width 0.1)
				(type default)
			)
			(layer "B.Fab")
		)
		(fp_line
			(start 0.12065 0.3048)
			(end 0.67945 0.3048)
			(stroke
				(width 0.1)
				(type default)
			)
			(layer "B.Fab")
		)
		(fp_line
			(start 0.67945 0.3048)
			(end 0.67945 -0.305054)
			(stroke
				(width 0.1)
				(type default)
			)
			(layer "B.Fab")
		)
		(fp_line
			(start -0.120396 0.2794)
			(end 0.12065 0.2794)
			(stroke
				(width 0.1)
				(type default)
			)
			(layer "B.Fab")
		)
		(fp_line
			(start 0.12065 0.2794)
			(end 0.12065 0.3048)
			(stroke
				(width 0.1)
				(type default)
			)
			(layer "B.Fab")
		)
		(fp_line
			(start -0.12065 -0.2794)
			(end -0.12065 -0.3048)
			(stroke
				(width 0.1)
				(type default)
			)
			(layer "B.Fab")
		)
		(fp_line
			(start 0.12065 -0.2794)
			(end -0.12065 -0.2794)
			(stroke
				(width 0.1)
				(type default)
			)
			(layer "B.Fab")
		)
		(fp_line
			(start -0.67945 -0.3048)
			(end -0.67945 0.3048)
			(stroke
				(width 0.1)
				(type default)
			)
			(layer "B.Fab")
		)
		(fp_line
			(start -0.12065 -0.3048)
			(end -0.67945 -0.3048)
			(stroke
				(width 0.1)
				(type default)
			)
			(layer "B.Fab")
		)
		(fp_line
			(start 0.12065 -0.305054)
			(end 0.12065 -0.2794)
			(stroke
				(width 0.1)
				(type default)
			)
			(layer "B.Fab")
		)
		(fp_line
			(start 0.67945 -0.305054)
			(end 0.12065 -0.305054)
			(stroke
				(width 0.1)
				(type default)
			)
			(layer "B.Fab")
		)
		(pad "1" smd circle
			(at 0.40005 0 90)
			(size 0 0)
			(layers "B.Cu" "B.Mask" "B.Paste")
			(net "PVNN_TERM_CPU0")
		)
		(pad "2" smd circle
			(at -0.40005 0 90)
			(size 0 0)
			(layers "B.Cu" "B.Mask" "B.Paste")
			(net "FM_S3M_CPU0_LVC1_GPIO_3")
		)
	)
)
